(kicad_pcb
	(version 20260206)
	(generator "pcbnew")
	(generator_version "10.0")
	(general
		(thickness 1.6)
		(legacy_teardrops no)
	)
	(paper "A4")
	(title_block
		(title "Bryce Canyon_F.DPB_16315-1-OCP.brd")
		(comment 1 "Bryce Canyon / footprints 578-584 of 2223")
	)
	(layers
		(0 "F.Cu" signal "TOP")
		(4 "In1.Cu" signal "L2GND")
		(6 "In2.Cu" signal "L3")
		(8 "In3.Cu" signal "L4GND")
		(10 "In4.Cu" signal "L5")
		(12 "In5.Cu" signal "L6VCC")
		(14 "In6.Cu" signal "L7VCC")
		(16 "In7.Cu" signal "L8")
		(18 "In8.Cu" signal "L9GND")
		(20 "In9.Cu" signal "L10")
		(22 "In10.Cu" signal "L11GND")
		(2 "B.Cu" signal "BOTTOM")
		(9 "F.Adhes" user "F.Adhesive")
		(11 "B.Adhes" user "B.Adhesive")
		(13 "F.Paste" user "Package Geometry/Pastemask Top")
		(15 "B.Paste" user "Package Geometry/Pastemask Bottom")
		(5 "F.SilkS" user "Ref Des/Silkscreen Top")
		(7 "B.SilkS" user "Ref Des/Silkscreen Bottom")
		(1 "F.Mask" user "Board Geometry/Soldermask Top")
		(3 "B.Mask" user "Board Geometry/Soldermask Bottom")
		(17 "Dwgs.User" user "User.Drawings")
		(19 "Cmts.User" user "User.Comments")
		(21 "Eco1.User" user "User.Eco1")
		(23 "Eco2.User" user "User.Eco2")
		(25 "Edge.Cuts" user "Board Geometry/Outline")
		(27 "Margin" user)
		(31 "F.CrtYd" user "Package Geometry/Place Bound Top")
		(29 "B.CrtYd" user "Package Geometry/Place Bound Bottom")
		(35 "F.Fab" user "Ref Des/Assembly Top")
		(33 "B.Fab" user "Ref Des/Assembly Bottom")
	)
	(footprint ""
		(layer "F.Cu")
		(at 237.996476 -349.211392)
		(property "Reference" "R27"
			(at 0 0 0)
			(layer "F.SilkS")
			(hide yes)
			(effects
				(font
					(size 1.27 1.27)
				)
			)
		)
		(property "Value" "7K32R2F-GP"
			(at 0.064008 -3.993896 0)
			(unlocked yes)
			(layer "F.Fab")
			(hide yes)
			(effects
				(font
					(size 1.016 1.016)
					(thickness 0.1524)
				)
			)
		)
		(property "Device Type" "R402H16"
			(at 0.064008 -5.517896 0)
			(unlocked yes)
			(layer "F.Fab")
			(hide yes)
			(effects
				(font
					(size 1.016 1.016)
					(thickness 0.1524)
				)
			)
		)
		(duplicate_pad_numbers_are_jumpers no)
		(fp_line
			(start -0.508 -0.9398)
			(end -0.508 0.9398)
			(stroke
				(width 0.1524)
				(type default)
			)
			(layer "F.SilkS")
		)
		(fp_line
			(start 0.508 -0.9398)
			(end -0.508 -0.9398)
			(stroke
				(width 0.1524)
				(type default)
			)
			(layer "F.SilkS")
		)
		(fp_rect
			(start -0.508 0.9398)
			(end 0.508 -0.9398)
			(stroke
				(width 0)
				(type default)
			)
			(fill no)
			(layer "F.CrtYd")
		)
		(fp_rect
			(start -0.508 0.9398)
			(end 0.508 -0.9398)
			(stroke
				(width 0)
				(type default)
			)
			(fill no)
			(layer "F.Fab")
		)
		(pad "1" smd custom
			(at 0 -0.4445)
			(size 0.1397 0.1397)
			(layers "F.Cu" "F.Mask" "F.Paste")
			(net "P3V3_STBY_A")
			(options
				(clearance outline)
				(anchor circle)
			)
			(primitives
				(gr_poly
					(pts
						(arc
							(start -0.1778 -0.2794)
							(mid -0.249642 -0.249642)
							(end -0.2794 -0.1778)
						)
						(arc
							(start -0.2794 0.1778)
							(mid -0.249642 0.249642)
							(end -0.1778 0.2794)
						)
						(arc
							(start 0.1778 0.2794)
							(mid 0.249642 0.249642)
							(end 0.2794 0.1778)
						)
						(arc
							(start 0.2794 -0.1778)
							(mid 0.249642 -0.249642)
							(end 0.1778 -0.2794)
						)
					)
					(width 0)
					(fill yes)
				)
			)
		)
		(pad "2" smd custom
			(at 0 0.4445)
			(size 0.1397 0.1397)
			(layers "F.Cu" "F.Mask" "F.Paste")
			(net "P3V3_SENSE")
			(options
				(clearance outline)
				(anchor circle)
			)
			(primitives
				(gr_poly
					(pts
						(arc
							(start -0.1778 -0.2794)
							(mid -0.249642 -0.249642)
							(end -0.2794 -0.1778)
						)
						(arc
							(start -0.2794 0.1778)
							(mid -0.249642 0.249642)
							(end -0.1778 0.2794)
						)
						(arc
							(start 0.1778 0.2794)
							(mid 0.249642 0.249642)
							(end 0.2794 0.1778)
						)
						(arc
							(start 0.2794 -0.1778)
							(mid 0.249642 -0.249642)
							(end 0.1778 -0.2794)
						)
					)
					(width 0)
					(fill yes)
				)
			)
		)
	)
	(footprint ""
		(layer "F.Cu")
		(at 353.184714 -273.660616 -90)
		(property "Reference" "C130"
			(at 0 0 270)
			(layer "F.SilkS")
			(hide yes)
			(effects
				(font
					(size 1.27 1.27)
				)
			)
		)
		(property "Value" "SCD01U16V1KX-GP"
			(at -2.8321 -1.7399 270)
			(unlocked yes)
			(layer "F.Fab")
			(hide yes)
			(effects
				(font
					(size 1.016 1.016)
					(thickness 0.1524)
				)
			)
		)
		(property "Device Type" "C0201H13"
			(at -2.8321 -3.2639 270)
			(unlocked yes)
			(layer "F.Fab")
			(hide yes)
			(effects
				(font
					(size 1.016 1.016)
					(thickness 0.1524)
				)
			)
		)
		(duplicate_pad_numbers_are_jumpers no)
		(fp_rect
			(start -0.2794 0.6477)
			(end 0.2794 -0.6477)
			(stroke
				(width 0)
				(type default)
			)
			(fill no)
			(layer "F.CrtYd")
		)
		(fp_rect
			(start -0.2794 0.6477)
			(end 0.2794 -0.6477)
			(stroke
				(width 0)
				(type default)
			)
			(fill no)
			(layer "F.Fab")
		)
		(pad "1" smd custom
			(at 0 -0.2794 270)
			(size 0.0762 0.0762)
			(layers "F.Cu" "F.Mask" "F.Paste")
			(net "SAS_HDD_RX_P7")
			(options
				(clearance outline)
				(anchor circle)
			)
			(primitives
				(gr_poly
					(pts
						(arc
							(start 0.1524 -0.127)
							(mid 0.137521 -0.162921)
							(end 0.1016 -0.1778)
						)
						(arc
							(start -0.1016 -0.1778)
							(mid -0.137521 -0.162921)
							(end -0.1524 -0.127)
						)
						(arc
							(start -0.1524 0.127)
							(mid -0.137521 0.162921)
							(end -0.1016 0.1778)
						)
						(arc
							(start 0.1016 0.1778)
							(mid 0.137521 0.162921)
							(end 0.1524 0.127)
						)
					)
					(width 0)
					(fill yes)
				)
			)
		)
		(pad "2" smd custom
			(at 0 0.2794 270)
			(size 0.0762 0.0762)
			(layers "F.Cu" "F.Mask" "F.Paste")
			(net "PHY_SCC_A_TO_DRV_A_7_DP")
			(options
				(clearance outline)
				(anchor circle)
			)
			(primitives
				(gr_poly
					(pts
						(arc
							(start 0.1524 -0.127)
							(mid 0.137521 -0.162921)
							(end 0.1016 -0.1778)
						)
						(arc
							(start -0.1016 -0.1778)
							(mid -0.137521 -0.162921)
							(end -0.1524 -0.127)
						)
						(arc
							(start -0.1524 0.127)
							(mid -0.137521 0.162921)
							(end -0.1016 0.1778)
						)
						(arc
							(start 0.1016 0.1778)
							(mid 0.137521 0.162921)
							(end 0.1524 0.127)
						)
					)
					(width 0)
					(fill yes)
				)
			)
		)
	)
	(footprint ""
		(layer "F.Cu")
		(at 263.09828 14.44117)
		(property "Reference" "U34"
			(at 0 0 0)
			(layer "F.SilkS")
			(hide yes)
			(effects
				(font
					(size 1.27 1.27)
				)
			)
		)
		(property "Value" "TPS2065DBVT-GP"
			(at 0 -5.1308 0)
			(unlocked yes)
			(layer "F.Fab")
			(hide yes)
			(effects
				(font
					(size 1.016 1.016)
					(thickness 0.1524)
				)
			)
		)
		(property "Device Type" "SOT-23-5H58"
			(at 0 -6.7564 0)
			(unlocked yes)
			(layer "F.Fab")
			(hide yes)
			(effects
				(font
					(size 1.016 1.016)
					(thickness 0.1524)
				)
			)
		)
		(duplicate_pad_numbers_are_jumpers no)
		(fp_line
			(start -1.778 -2.286)
			(end -1.778 2.286)
			(stroke
				(width 0.1524)
				(type default)
			)
			(layer "F.SilkS")
		)
		(fp_line
			(start -1.778 2.286)
			(end -0.254 2.286)
			(stroke
				(width 0.1524)
				(type default)
			)
			(layer "F.SilkS")
		)
		(fp_line
			(start -1.778 2.286)
			(end 1.778 2.286)
			(stroke
				(width 0.1524)
				(type default)
			)
			(layer "F.SilkS")
		)
		(fp_line
			(start -1.7272 2.2352)
			(end -1.7272 0.762)
			(stroke
				(width 0.3302)
				(type default)
			)
			(layer "F.SilkS")
		)
		(fp_line
			(start -0.7112 2.2352)
			(end -1.7272 2.2352)
			(stroke
				(width 0.3302)
				(type default)
			)
			(layer "F.SilkS")
		)
		(fp_line
			(start -0.254 2.286)
			(end 1.778 2.286)
			(stroke
				(width 0.1524)
				(type default)
			)
			(layer "F.SilkS")
		)
		(fp_line
			(start 1.778 -2.286)
			(end -1.778 -2.286)
			(stroke
				(width 0.1524)
				(type default)
			)
			(layer "F.SilkS")
		)
		(fp_line
			(start 1.778 2.286)
			(end 1.778 -2.286)
			(stroke
				(width 0.1524)
				(type default)
			)
			(layer "F.SilkS")
		)
		(fp_poly
			(pts
				(xy -0.9652 2.4384) (xy -1.3208 2.794) (xy -0.6096 2.794)
			)
			(stroke
				(width 0)
				(type default)
			)
			(fill yes)
			(layer "F.SilkS")
		)
		(fp_rect
			(start -1.778 2.286)
			(end 1.778 -2.286)
			(stroke
				(width 0)
				(type default)
			)
			(fill no)
			(layer "F.CrtYd")
		)
		(fp_rect
			(start -1.778 2.286)
			(end 1.778 -2.286)
			(stroke
				(width 0)
				(type default)
			)
			(fill no)
			(layer "F.Fab")
		)
		(pad "1" smd rect
			(at -0.94996 1.143)
			(size 0.508 1.524)
			(layers "F.Cu" "F.Mask" "F.Paste")
			(net "P5V_USB_A")
		)
		(pad "2" smd rect
			(at 0 1.143)
			(size 0.508 1.524)
			(layers "F.Cu" "F.Mask" "F.Paste")
			(net "GND")
		)
		(pad "3" smd rect
			(at 0.94996 1.143)
			(size 0.508 1.524)
			(layers "F.Cu" "F.Mask" "F.Paste")
			(net "USB_OCS_N1")
		)
		(pad "4" smd rect
			(at 0.94996 -1.143)
			(size 0.508 1.524)
			(layers "F.Cu" "F.Mask" "F.Paste")
			(net "USB_EN_1")
		)
		(pad "5" smd rect
			(at -0.94996 -1.143)
			(size 0.508 1.524)
			(layers "F.Cu" "F.Mask" "F.Paste")
			(net "P5V_A_2")
		)
	)
	(footprint ""
		(layer "F.Cu")
		(at 190.213488 -274.219416 90)
		(property "Reference" "C103"
			(at 0 0 90)
			(layer "F.SilkS")
			(hide yes)
			(effects
				(font
					(size 1.27 1.27)
				)
			)
		)
		(property "Value" "SCD01U16V1KX-GP"
			(at -2.8321 -1.7399 90)
			(unlocked yes)
			(layer "F.Fab")
			(hide yes)
			(effects
				(font
					(size 1.016 1.016)
					(thickness 0.1524)
				)
			)
		)
		(property "Device Type" "C0201H13"
			(at -2.8321 -3.2639 90)
			(unlocked yes)
			(layer "F.Fab")
			(hide yes)
			(effects
				(font
					(size 1.016 1.016)
					(thickness 0.1524)
				)
			)
		)
		(duplicate_pad_numbers_are_jumpers no)
		(fp_rect
			(start -0.2794 0.6477)
			(end 0.2794 -0.6477)
			(stroke
				(width 0)
				(type default)
			)
			(fill no)
			(layer "F.CrtYd")
		)
		(fp_rect
			(start -0.2794 0.6477)
			(end 0.2794 -0.6477)
			(stroke
				(width 0)
				(type default)
			)
			(fill no)
			(layer "F.Fab")
		)
		(pad "1" smd custom
			(at 0 -0.2794 90)
			(size 0.0762 0.0762)
			(layers "F.Cu" "F.Mask" "F.Paste")
			(net "SAS_HDD_RX_N5")
			(options
				(clearance outline)
				(anchor circle)
			)
			(primitives
				(gr_poly
					(pts
						(arc
							(start 0.1524 -0.127)
							(mid 0.137521 -0.162921)
							(end 0.1016 -0.1778)
						)
						(arc
							(start -0.1016 -0.1778)
							(mid -0.137521 -0.162921)
							(end -0.1524 -0.127)
						)
						(arc
							(start -0.1524 0.127)
							(mid -0.137521 0.162921)
							(end -0.1016 0.1778)
						)
						(arc
							(start 0.1016 0.1778)
							(mid 0.137521 0.162921)
							(end 0.1524 0.127)
						)
					)
					(width 0)
					(fill yes)
				)
			)
		)
		(pad "2" smd custom
			(at 0 0.2794 90)
			(size 0.0762 0.0762)
			(layers "F.Cu" "F.Mask" "F.Paste")
			(net "PHY_SCC_A_TO_DRV_A_5_DN")
			(options
				(clearance outline)
				(anchor circle)
			)
			(primitives
				(gr_poly
					(pts
						(arc
							(start 0.1524 -0.127)
							(mid 0.137521 -0.162921)
							(end 0.1016 -0.1778)
						)
						(arc
							(start -0.1016 -0.1778)
							(mid -0.137521 -0.162921)
							(end -0.1524 -0.127)
						)
						(arc
							(start -0.1524 0.127)
							(mid -0.137521 0.162921)
							(end -0.1016 0.1778)
						)
						(arc
							(start 0.1016 0.1778)
							(mid 0.137521 0.162921)
							(end 0.1524 0.127)
						)
					)
					(width 0)
					(fill yes)
				)
			)
		)
	)
	(footprint ""
		(layer "F.Cu")
		(at 175.550068 -94.400116)
		(property "Reference" "FLED18"
			(at 0 0 0)
			(layer "F.SilkS")
			(hide yes)
			(effects
				(font
					(size 1.27 1.27)
				)
			)
		)
		(property "Value" "LED-BY-19-GP"
			(at -2.132076 1.414018 0)
			(unlocked yes)
			(layer "F.Fab")
			(hide yes)
			(effects
				(font
					(size 1.016 1.016)
					(thickness 0.1524)
				)
			)
		)
		(property "Device Type" "LED-1615-4PH26"
			(at -2.132076 -0.109982 0)
			(unlocked yes)
			(layer "F.Fab")
			(hide yes)
			(effects
				(font
					(size 1.016 1.016)
					(thickness 0.1524)
				)
			)
		)
		(duplicate_pad_numbers_are_jumpers no)
		(fp_line
			(start -1.2954 0.254)
			(end -1.2954 1.6002)
			(stroke
				(width 0.508)
				(type default)
			)
			(layer "F.SilkS")
		)
		(fp_line
			(start -1.2954 1.6002)
			(end 1.2954 1.6002)
			(stroke
				(width 0.508)
				(type default)
			)
			(layer "F.SilkS")
		)
		(fp_line
			(start -1.1176 -1.4224)
			(end 1.1176 -1.4224)
			(stroke
				(width 0.1524)
				(type default)
			)
			(layer "F.SilkS")
		)
		(fp_line
			(start -1.1176 1.4224)
			(end -1.1176 -1.4224)
			(stroke
				(width 0.1524)
				(type default)
			)
			(layer "F.SilkS")
		)
		(fp_line
			(start 1.1176 -1.4224)
			(end 1.1176 1.4224)
			(stroke
				(width 0.1524)
				(type default)
			)
			(layer "F.SilkS")
		)
		(fp_line
			(start 1.1176 1.4224)
			(end -1.1176 1.4224)
			(stroke
				(width 0.1524)
				(type default)
			)
			(layer "F.SilkS")
		)
		(fp_line
			(start 1.2954 1.6002)
			(end 1.2954 0.254)
			(stroke
				(width 0.508)
				(type default)
			)
			(layer "F.SilkS")
		)
		(fp_rect
			(start -0.7493 0.8001)
			(end 0.7493 -0.8001)
			(stroke
				(width 0)
				(type default)
			)
			(fill no)
			(layer "F.CrtYd")
		)
		(fp_poly
			(pts
				(xy -1.3716 1.6764) (xy -1.3716 -1.6764) (xy 1.3716 -1.6764) (xy 1.3716 0.0635) (xy 0.7493 0.0635)
				(xy 0.7493 -0.8001) (xy -0.7493 -0.8001) (xy -0.7493 0.8001) (xy 0.7493 0.8001) (xy 0.7493 0.0762)
				(xy 1.3716 0.0762) (xy 1.3716 1.6764)
			)
			(stroke
				(width 0)
				(type default)
			)
			(fill no)
			(layer "F.CrtYd")
		)
		(fp_rect
			(start -1.3716 1.6764)
			(end 1.3716 -1.6764)
			(stroke
				(width 0)
				(type default)
			)
			(fill no)
			(layer "F.Fab")
		)
		(pad "1" smd rect
			(at 0.50038 -0.73025)
			(size 0.7112 0.8636)
			(layers "F.Cu" "F.Mask" "F.Paste")
			(net "DRV_ACT_17")
		)
		(pad "2" smd rect
			(at -0.50038 -0.73025)
			(size 0.7112 0.8636)
			(layers "F.Cu" "F.Mask" "F.Paste")
			(net "FLT_HDD17")
		)
		(pad "3" smd rect
			(at 0.50038 0.73025)
			(size 0.7112 0.8636)
			(layers "F.Cu" "F.Mask" "F.Paste")
			(net "DRV_ACT_17_N")
		)
		(pad "4" smd rect
			(at -0.50038 0.73025)
			(size 0.7112 0.8636)
			(layers "F.Cu" "F.Mask" "F.Paste")
			(net "FLT_HDD17_N")
		)
	)
	(footprint ""
		(layer "F.Cu")
		(at 333.586836 -184.450228 -90)
		(property "Reference" "R545"
			(at 0 0 270)
			(layer "F.SilkS")
			(hide yes)
			(effects
				(font
					(size 1.27 1.27)
				)
			)
		)
		(property "Value" "2R6F-GP"
			(at -0.0508 -4.8514 270)
			(unlocked yes)
			(layer "F.Fab")
			(hide yes)
			(effects
				(font
					(size 1.016 1.016)
					(thickness 0.1524)
				)
			)
		)
		(property "Device Type" "R1206H26"
			(at 0 -6.3754 270)
			(unlocked yes)
			(layer "F.Fab")
			(hide yes)
			(effects
				(font
					(size 1.016 1.016)
					(thickness 0.1524)
				)
			)
		)
		(duplicate_pad_numbers_are_jumpers no)
		(fp_line
			(start -1.016 2.2352)
			(end -1.016 -2.2352)
			(stroke
				(width 0.1524)
				(type default)
			)
			(layer "F.SilkS")
		)
		(fp_line
			(start 1.016 2.2352)
			(end -1.016 2.2352)
			(stroke
				(width 0.1524)
				(type default)
			)
			(layer "F.SilkS")
		)
		(fp_line
			(start -1.016 -2.2352)
			(end 1.016 -2.2352)
			(stroke
				(width 0.1524)
				(type default)
			)
			(layer "F.SilkS")
		)
		(fp_line
			(start 1.016 -2.2352)
			(end 1.016 2.2352)
			(stroke
				(width 0.1524)
				(type default)
			)
			(layer "F.SilkS")
		)
		(fp_rect
			(start -1.0922 2.3114)
			(end 1.0922 -2.3114)
			(stroke
				(width 0)
				(type default)
			)
			(fill no)
			(layer "F.CrtYd")
		)
		(fp_poly
			(pts
				(xy -1.0922 -2.3114) (xy 1.0922 -2.3114) (xy 1.0922 2.3114) (xy -1.0922 2.3114)
			)
			(stroke
				(width 0)
				(type default)
			)
			(fill no)
			(layer "F.Fab")
		)
		(pad "1" smd rect
			(at 0 -1.397 270)
			(size 1.651 1.27)
			(layers "F.Cu" "F.Mask" "F.Paste")
			(net "P12V_HDD18")
		)
		(pad "2" smd rect
			(at 0 1.397 270)
			(size 1.651 1.27)
			(layers "F.Cu" "F.Mask" "F.Paste")
			(net "12V_PRE_18")
		)
	)
	(footprint ""
		(layer "F.Cu")
		(at 49.349914 -209.399886)
		(property "Reference" "FLED2"
			(at 0 0 0)
			(layer "F.SilkS")
			(hide yes)
			(effects
				(font
					(size 1.27 1.27)
				)
			)
		)
		(property "Value" "LED-BY-19-GP"
			(at -2.132076 1.414018 0)
			(unlocked yes)
			(layer "F.Fab")
			(hide yes)
			(effects
				(font
					(size 1.016 1.016)
					(thickness 0.1524)
				)
			)
		)
		(property "Device Type" "LED-1615-4PH26"
			(at -2.132076 -0.109982 0)
			(unlocked yes)
			(layer "F.Fab")
			(hide yes)
			(effects
				(font
					(size 1.016 1.016)
					(thickness 0.1524)
				)
			)
		)
		(duplicate_pad_numbers_are_jumpers no)
		(fp_line
			(start -1.2954 0.254)
			(end -1.2954 1.6002)
			(stroke
				(width 0.508)
				(type default)
			)
			(layer "F.SilkS")
		)
		(fp_line
			(start -1.2954 1.6002)
			(end 1.2954 1.6002)
			(stroke
				(width 0.508)
				(type default)
			)
			(layer "F.SilkS")
		)
		(fp_line
			(start -1.1176 -1.4224)
			(end 1.1176 -1.4224)
			(stroke
				(width 0.1524)
				(type default)
			)
			(layer "F.SilkS")
		)
		(fp_line
			(start -1.1176 1.4224)
			(end -1.1176 -1.4224)
			(stroke
				(width 0.1524)
				(type default)
			)
			(layer "F.SilkS")
		)
		(fp_line
			(start 1.1176 -1.4224)
			(end 1.1176 1.4224)
			(stroke
				(width 0.1524)
				(type default)
			)
			(layer "F.SilkS")
		)
		(fp_line
			(start 1.1176 1.4224)
			(end -1.1176 1.4224)
			(stroke
				(width 0.1524)
				(type default)
			)
			(layer "F.SilkS")
		)
		(fp_line
			(start 1.2954 1.6002)
			(end 1.2954 0.254)
			(stroke
				(width 0.508)
				(type default)
			)
			(layer "F.SilkS")
		)
		(fp_rect
			(start -0.7493 0.8001)
			(end 0.7493 -0.8001)
			(stroke
				(width 0)
				(type default)
			)
			(fill no)
			(layer "F.CrtYd")
		)
		(fp_poly
			(pts
				(xy -1.3716 1.6764) (xy -1.3716 -1.6764) (xy 1.3716 -1.6764) (xy 1.3716 0.0635) (xy 0.7493 0.0635)
				(xy 0.7493 -0.8001) (xy -0.7493 -0.8001) (xy -0.7493 0.8001) (xy 0.7493 0.8001) (xy 0.7493 0.0762)
				(xy 1.3716 0.0762) (xy 1.3716 1.6764)
			)
			(stroke
				(width 0)
				(type default)
			)
			(fill no)
			(layer "F.CrtYd")
		)
		(fp_rect
			(start -1.3716 1.6764)
			(end 1.3716 -1.6764)
			(stroke
				(width 0)
				(type default)
			)
			(fill no)
			(layer "F.Fab")
		)
		(pad "1" smd rect
			(at 0.50038 -0.73025)
			(size 0.7112 0.8636)
			(layers "F.Cu" "F.Mask" "F.Paste")
			(net "DRV_ACT_1")
		)
		(pad "2" smd rect
			(at -0.50038 -0.73025)
			(size 0.7112 0.8636)
			(layers "F.Cu" "F.Mask" "F.Paste")
			(net "FLT_HDD1")
		)
		(pad "3" smd rect
			(at 0.50038 0.73025)
			(size 0.7112 0.8636)
			(layers "F.Cu" "F.Mask" "F.Paste")
			(net "DRV_ACT_1_N")
		)
		(pad "4" smd rect
			(at -0.50038 0.73025)
			(size 0.7112 0.8636)
			(layers "F.Cu" "F.Mask" "F.Paste")
			(net "FLT_HDD1_N")
		)
	)
)
